# T6G (Grand Teton) — schematic netlist excerpt (pin names and nets, part order shuffled) for the footprints in the layout excerpt that follows; sources: Cadence DE-HDL packaged netlist, KiCad conversion of 04192023_DAF0TMB3IC0_F0TG_MB_C_brd_V02_OCP.brd

PU203  MAX15090BEWIT  MAX15090BEWI+T IC  pkg BGA28_0-5_3-525X2-065  page 134
  ISENSE  = P12V_OCP_SENSE_1
  VCC  = P12V_OCP_VCC_1
  IN_A3  = P12V_AUX
  OUT_A4  = P12V_OCP_SFF
  IN_A5  = P12V_AUX
  GATE  = P12V_OCP_GATE_1
  CDLY  = GND
  CB  = P12V_OCP_CB_1
  GND_B2  = GND
  IN_B3  = P12V_AUX
  OUT_B4  = P12V_OCP_SFF
  IN_B5  = P12V_AUX
  OUT_B6  = P12V_OCP_SFF
  \en#\  = GND
  GND_C1  = GND
  GND_C2  = GND
  IN_C3  = P12V_AUX
  OUT_C4  = P12V_OCP_SFF
  IN_C5  = P12V_AUX
  OUT_C6  = P12V_OCP_SFF
  \fault#\  = P12V_OCP_FAULT_1
  REG  = P12V_OCP_REG_1
  UV  = P12V_OCP_UV_1
  OV  = P12V_OCP_OV_1
  OUT_D4  = P12V_OCP_SFF
  IN_D5  = P12V_AUX
  OUT_D6  = P12V_OCP_SFF
  PG  = P12V_OCP_PWRGD_1

(kicad_pcb
	(version 20260206)
	(generator "pcbnew")
	(generator_version "10.0")
	(general
		(thickness 1.6)
		(legacy_teardrops no)
	)
	(paper "A4")
	(title_block
		(title "04192023_DAF0TMB3IC0_F0TG_MB_C_brd_V02_OCP.brd")
		(comment 1 "Grand Teton / footprints 2649-2649 of 8354")
	)
	(layers
		(0 "F.Cu" signal "TOP")
		(4 "In1.Cu" signal "GND")
		(6 "In2.Cu" signal "IN1")
		(8 "In3.Cu" signal "GND1")
		(10 "In4.Cu" signal "IN2")
		(12 "In5.Cu" signal "GND2")
		(14 "In6.Cu" signal "IN3")
		(16 "In7.Cu" signal "GND3")
		(18 "In8.Cu" signal "VCC")
		(20 "In9.Cu" signal "VCC1")
		(22 "In10.Cu" signal "GND4")
		(24 "In11.Cu" signal "IN4")
		(26 "In12.Cu" signal "GND5")
		(28 "In13.Cu" signal "IN5")
		(30 "In14.Cu" signal "GND6")
		(32 "In15.Cu" signal "IN6")
		(34 "In16.Cu" signal "GND7")
		(2 "B.Cu" signal "BOTTOM")
		(9 "F.Adhes" user "F.Adhesive")
		(11 "B.Adhes" user "B.Adhesive")
		(13 "F.Paste" user "Package Geometry/Pastemask Top")
		(15 "B.Paste" user "Package Geometry/Pastemask Bottom")
		(5 "F.SilkS" user "Ref Des/Silkscreen Top")
		(7 "B.SilkS" user "Ref Des/Silkscreen Bottom")
		(1 "F.Mask" user "Board Geometry/Soldermask Top")
		(3 "B.Mask" user "Board Geometry/Soldermask Bottom")
		(17 "Dwgs.User" user "User.Drawings")
		(19 "Cmts.User" user "User.Comments")
		(21 "Eco1.User" user "User.Eco1")
		(23 "Eco2.User" user "User.Eco2")
		(25 "Edge.Cuts" user "Board Geometry/Outline")
		(27 "Margin" user)
		(31 "F.CrtYd" user "Package Geometry/Place Bound Top")
		(29 "B.CrtYd" user "Package Geometry/Place Bound Bottom")
		(35 "F.Fab" user "Ref Des/Assembly Top")
		(33 "B.Fab" user "Ref Des/Assembly Bottom")
	)
	(footprint ""
		(layer "F.Cu")
		(at 451.497192 -20.979638)
		(property "Reference" "PU203"
			(at 2.76479 -1.83896 0)
			(unlocked yes)
			(layer "F.SilkS")
			(effects
				(font
					(size 0.7874 0.5842)
					(thickness 0.1524)
				)
				(justify left)
			)
		)
		(property "Value" ""
			(at 0 0 0)
			(layer "F.Fab")
			(effects
				(font
					(size 1.27 1.27)
				)
			)
		)
		(duplicate_pad_numbers_are_jumpers no)
		(fp_line
			(start -1.774952 -1.039876)
			(end -1.774952 1.039876)
			(stroke
				(width 0.1524)
				(type default)
			)
			(layer "F.SilkS")
		)
		(fp_line
			(start -1.774952 1.039876)
			(end 1.774952 1.039876)
			(stroke
				(width 0.1524)
				(type default)
			)
			(layer "F.SilkS")
		)
		(fp_line
			(start 1.774952 -1.039876)
			(end -1.774952 -1.039876)
			(stroke
				(width 0.1524)
				(type default)
			)
			(layer "F.SilkS")
		)
		(fp_line
			(start 1.774952 1.039876)
			(end 1.774952 -1.039876)
			(stroke
				(width 0.1524)
				(type default)
			)
			(layer "F.SilkS")
		)
		(fp_poly
			(pts
				(xy -0.999998 -1.801876) (xy -0.999998 -1.039876) (xy -1.769872 -1.039876) (xy -1.769872 -0.249936)
				(xy -2.531872 -0.249936) (xy -2.531872 -1.801876)
			)
			(stroke
				(width 0)
				(type default)
			)
			(fill yes)
			(layer "F.SilkS")
		)
		(fp_line
			(start -1.769872 -1.039876)
			(end -1.769872 1.039876)
			(stroke
				(width 0.1)
				(type default)
			)
			(layer "F.Fab")
		)
		(fp_line
			(start -1.769872 1.039876)
			(end 1.769872 1.039876)
			(stroke
				(width 0.1)
				(type default)
			)
			(layer "F.Fab")
		)
		(fp_line
			(start 1.769872 -1.039876)
			(end -1.769872 -1.039876)
			(stroke
				(width 0.1)
				(type default)
			)
			(layer "F.Fab")
		)
		(fp_line
			(start 1.769872 1.039876)
			(end 1.769872 -1.039876)
			(stroke
				(width 0.1)
				(type default)
			)
			(layer "F.Fab")
		)
		(fp_poly
			(pts
				(xy -1.769872 -1.039876) (xy -0.999998 -1.039876) (xy -0.999998 -1.801876) (xy -2.531872 -1.801876)
				(xy -2.531872 -0.249936) (xy -1.769872 -0.249936)
			)
			(stroke
				(width 0)
				(type default)
			)
			(fill yes)
			(layer "F.Fab")
		)
		(pad "A1" smd circle
			(at -1.500124 -0.750062)
			(size 0.2286 0.2286)
			(layers "F.Cu" "F.Mask" "F.Paste")
			(net "P12V_OCP_SENSE_1")
		)
		(pad "A2" smd circle
			(at -0.999998 -0.750062)
			(size 0.2286 0.2286)
			(layers "F.Cu" "F.Mask" "F.Paste")
			(net "P12V_OCP_VCC_1")
		)
		(pad "A3" smd circle
			(at -0.499872 -0.750062)
			(size 0.2286 0.2286)
			(layers "F.Cu" "F.Mask" "F.Paste")
			(net "P12V_AUX")
		)
		(pad "A4" smd circle
			(at 0 -0.750062)
			(size 0.2286 0.2286)
			(layers "F.Cu" "F.Mask" "F.Paste")
			(net "P12V_OCP_SFF")
		)
		(pad "A5" smd circle
			(at 0.499872 -0.750062)
			(size 0.2286 0.2286)
			(layers "F.Cu" "F.Mask" "F.Paste")
			(net "P12V_AUX")
		)
		(pad "A6" smd circle
			(at 0.999998 -0.750062)
			(size 0.2286 0.2286)
			(layers "F.Cu" "F.Mask" "F.Paste")
			(net "P12V_OCP_GATE_1")
		)
		(pad "A7" smd circle
			(at 1.500124 -0.750062)
			(size 0.2286 0.2286)
			(layers "F.Cu" "F.Mask" "F.Paste")
			(net "GND")
		)
		(pad "B1" smd circle
			(at -1.500124 -0.249936)
			(size 0.2286 0.2286)
			(layers "F.Cu" "F.Mask" "F.Paste")
			(net "P12V_OCP_CB_1")
		)
		(pad "B2" smd circle
			(at -0.999998 -0.249936)
			(size 0.2286 0.2286)
			(layers "F.Cu" "F.Mask" "F.Paste")
			(net "GND")
		)
		(pad "B3" smd circle
			(at -0.499872 -0.249936)
			(size 0.2286 0.2286)
			(layers "F.Cu" "F.Mask" "F.Paste")
			(net "P12V_AUX")
		)
		(pad "B4" smd circle
			(at 0 -0.249936)
			(size 0.2286 0.2286)
			(layers "F.Cu" "F.Mask" "F.Paste")
			(net "P12V_OCP_SFF")
		)
		(pad "B5" smd circle
			(at 0.499872 -0.249936)
			(size 0.2286 0.2286)
			(layers "F.Cu" "F.Mask" "F.Paste")
			(net "P12V_AUX")
		)
		(pad "B6" smd circle
			(at 0.999998 -0.249936)
			(size 0.2286 0.2286)
			(layers "F.Cu" "F.Mask" "F.Paste")
			(net "P12V_OCP_SFF")
		)
		(pad "B7" smd circle
			(at 1.500124 -0.249936)
			(size 0.2286 0.2286)
			(layers "F.Cu" "F.Mask" "F.Paste")
			(net "GND")
		)
		(pad "C1" smd circle
			(at -1.500124 0.249936)
			(size 0.2286 0.2286)
			(layers "F.Cu" "F.Mask" "F.Paste")
			(net "GND")
		)
		(pad "C2" smd circle
			(at -0.999998 0.249936)
			(size 0.2286 0.2286)
			(layers "F.Cu" "F.Mask" "F.Paste")
			(net "GND")
		)
		(pad "C3" smd circle
			(at -0.499872 0.249936)
			(size 0.2286 0.2286)
			(layers "F.Cu" "F.Mask" "F.Paste")
			(net "P12V_AUX")
		)
		(pad "C4" smd circle
			(at 0 0.249936)
			(size 0.2286 0.2286)
			(layers "F.Cu" "F.Mask" "F.Paste")
			(net "P12V_OCP_SFF")
		)
		(pad "C5" smd circle
			(at 0.499872 0.249936)
			(size 0.2286 0.2286)
			(layers "F.Cu" "F.Mask" "F.Paste")
			(net "P12V_AUX")
		)
		(pad "C6" smd circle
			(at 0.999998 0.249936)
			(size 0.2286 0.2286)
			(layers "F.Cu" "F.Mask" "F.Paste")
			(net "P12V_OCP_SFF")
		)
		(pad "C7" smd circle
			(at 1.500124 0.249936)
			(size 0.2286 0.2286)
			(layers "F.Cu" "F.Mask" "F.Paste")
			(net "P12V_OCP_FAULT_1")
		)
		(pad "D1" smd circle
			(at -1.500124 0.750062)
			(size 0.2286 0.2286)
			(layers "F.Cu" "F.Mask" "F.Paste")
			(net "P12V_OCP_REG_1")
		)
		(pad "D2" smd circle
			(at -0.999998 0.750062)
			(size 0.2286 0.2286)
			(layers "F.Cu" "F.Mask" "F.Paste")
			(net "P12V_OCP_UV_1")
		)
		(pad "D3" smd circle
			(at -0.499872 0.750062)
			(size 0.2286 0.2286)
			(layers "F.Cu" "F.Mask" "F.Paste")
			(net "P12V_OCP_OV_1")
		)
		(pad "D4" smd circle
			(at 0 0.750062)
			(size 0.2286 0.2286)
			(layers "F.Cu" "F.Mask" "F.Paste")
			(net "P12V_OCP_SFF")
		)
		(pad "D5" smd circle
			(at 0.499872 0.750062)
			(size 0.2286 0.2286)
			(layers "F.Cu" "F.Mask" "F.Paste")
			(net "P12V_AUX")
		)
		(pad "D6" smd circle
			(at 0.999998 0.750062)
			(size 0.2286 0.2286)
			(layers "F.Cu" "F.Mask" "F.Paste")
			(net "P12V_OCP_SFF")
		)
		(pad "D7" smd circle
			(at 1.500124 0.750062)
			(size 0.2286 0.2286)
			(layers "F.Cu" "F.Mask" "F.Paste")
			(net "P12V_OCP_PWRGD_1")
		)
	)
)
